(kicad_pcb
	(version 20260206)
	(generator "pcbnew")
	(generator_version "10.0")
	(general
		(thickness 1.6)
		(legacy_teardrops no)
	)
	(paper "A4")
	(title_block
		(title "dpb — 14545-sa.0730WZS0815.brd")
		(comment 1 "Honey Badger (Wiwynn) / footprints 532-539 of 1066")
	)
	(layers
		(0 "F.Cu" signal "TOP")
		(4 "In1.Cu" signal "L2GND")
		(6 "In2.Cu" signal "L3")
		(8 "In3.Cu" signal "L4VCC")
		(10 "In4.Cu" signal "L5VCC")
		(12 "In5.Cu" signal "L6")
		(14 "In6.Cu" signal "L7GND")
		(2 "B.Cu" signal "BOTTOM")
		(9 "F.Adhes" user "F.Adhesive")
		(11 "B.Adhes" user "B.Adhesive")
		(13 "F.Paste" user "Package Geometry/Pastemask Top")
		(15 "B.Paste" user "Package Geometry/Pastemask Bottom")
		(5 "F.SilkS" user "Ref Des/Silkscreen Top")
		(7 "B.SilkS" user "Ref Des/Silkscreen Bottom")
		(1 "F.Mask" user "Board Geometry/Soldermask Top")
		(3 "B.Mask" user "Board Geometry/Soldermask Bottom")
		(17 "Dwgs.User" user "User.Drawings")
		(19 "Cmts.User" user "User.Comments")
		(21 "Eco1.User" user "User.Eco1")
		(23 "Eco2.User" user "User.Eco2")
		(25 "Edge.Cuts" user "Board Geometry/Outline")
		(27 "Margin" user)
		(31 "F.CrtYd" user "Package Geometry/Place Bound Top")
		(29 "B.CrtYd" user "Package Geometry/Place Bound Bottom")
		(35 "F.Fab" user "Ref Des/Assembly Top")
		(33 "B.Fab" user "Ref Des/Assembly Bottom")
	)
	(footprint ""
		(layer "F.Cu")
		(at 27.304746 -436.019702 90)
		(property "Reference" "R460"
			(at 0 0 90)
			(layer "F.SilkS")
			(hide yes)
			(effects
				(font
					(size 1.27 1.27)
				)
			)
		)
		(property "Value" "4K7R2J-2-GP"
			(at 0.064008 -3.993896 90)
			(unlocked yes)
			(layer "F.Fab")
			(hide yes)
			(effects
				(font
					(size 1.016 1.016)
					(thickness 0.1524)
				)
			)
		)
		(property "Device Type" "R402H16"
			(at 0.064008 -5.517896 90)
			(unlocked yes)
			(layer "F.Fab")
			(hide yes)
			(effects
				(font
					(size 1.016 1.016)
					(thickness 0.1524)
				)
			)
		)
		(duplicate_pad_numbers_are_jumpers no)
		(fp_line
			(start 0.508 -0.9398)
			(end -0.508 -0.9398)
			(stroke
				(width 0.1524)
				(type default)
			)
			(layer "F.SilkS")
		)
		(fp_line
			(start -0.508 -0.9398)
			(end -0.508 0.9398)
			(stroke
				(width 0.1524)
				(type default)
			)
			(layer "F.SilkS")
		)
		(fp_rect
			(start -0.508 0.9398)
			(end 0.508 -0.9398)
			(stroke
				(width 0)
				(type default)
			)
			(fill no)
			(layer "F.CrtYd")
		)
		(fp_rect
			(start -0.508 0.9398)
			(end 0.508 -0.9398)
			(stroke
				(width 0)
				(type default)
			)
			(fill no)
			(layer "F.Fab")
		)
		(pad "1" smd custom
			(at 0 -0.4445 90)
			(size 0.1397 0.1397)
			(layers "F.Cu" "F.Mask" "F.Paste")
			(net "P3V3")
			(options
				(clearance outline)
				(anchor circle)
			)
			(primitives
				(gr_poly
					(pts
						(arc
							(start -0.1778 -0.2794)
							(mid -0.249642 -0.249642)
							(end -0.2794 -0.1778)
						)
						(arc
							(start -0.2794 0.1778)
							(mid -0.249642 0.249642)
							(end -0.1778 0.2794)
						)
						(arc
							(start 0.1778 0.2794)
							(mid 0.249642 0.249642)
							(end 0.2794 0.1778)
						)
						(arc
							(start 0.2794 -0.1778)
							(mid 0.249642 -0.249642)
							(end 0.1778 -0.2794)
						)
					)
					(width 0)
					(fill yes)
				)
			)
		)
		(pad "2" smd custom
			(at 0 0.4445 90)
			(size 0.1397 0.1397)
			(layers "F.Cu" "F.Mask" "F.Paste")
			(net "SAS2X28_A_HDD10_FLT")
			(options
				(clearance outline)
				(anchor circle)
			)
			(primitives
				(gr_poly
					(pts
						(arc
							(start -0.1778 -0.2794)
							(mid -0.249642 -0.249642)
							(end -0.2794 -0.1778)
						)
						(arc
							(start -0.2794 0.1778)
							(mid -0.249642 0.249642)
							(end -0.1778 0.2794)
						)
						(arc
							(start 0.1778 0.2794)
							(mid 0.249642 0.249642)
							(end 0.2794 0.1778)
						)
						(arc
							(start 0.2794 -0.1778)
							(mid 0.249642 -0.249642)
							(end 0.1778 -0.2794)
						)
					)
					(width 0)
					(fill yes)
				)
			)
		)
	)
	(footprint ""
		(layer "F.Cu")
		(at 208.026 -478.79 -90)
		(property "Reference" "Q31"
			(at 0 0 270)
			(layer "F.SilkS")
			(hide yes)
			(effects
				(font
					(size 1.27 1.27)
				)
			)
		)
		(property "Value" "2N7002DW-7F-GP"
			(at -2.3622 -8.2042 270)
			(unlocked yes)
			(layer "F.Fab")
			(hide yes)
			(effects
				(font
					(size 1.016 1.016)
					(thickness 0.1524)
				)
			)
		)
		(property "Device Type" "SOT-363H44"
			(at -2.3622 -10.1092 270)
			(unlocked yes)
			(layer "F.Fab")
			(hide yes)
			(effects
				(font
					(size 1.016 1.016)
					(thickness 0.1524)
				)
			)
		)
		(duplicate_pad_numbers_are_jumpers no)
		(fp_line
			(start -1.4478 1.7018)
			(end 1.4478 1.7018)
			(stroke
				(width 0.1524)
				(type default)
			)
			(layer "F.SilkS")
		)
		(fp_line
			(start 1.4478 1.7018)
			(end 1.4478 -1.7018)
			(stroke
				(width 0.1524)
				(type default)
			)
			(layer "F.SilkS")
		)
		(fp_line
			(start -1.27 1.524)
			(end -1.27 0.6604)
			(stroke
				(width 0.4826)
				(type default)
			)
			(layer "F.SilkS")
		)
		(fp_line
			(start -1.4478 -1.7018)
			(end -1.4478 1.7018)
			(stroke
				(width 0.1524)
				(type default)
			)
			(layer "F.SilkS")
		)
		(fp_line
			(start 1.4478 -1.7018)
			(end -1.4478 -1.7018)
			(stroke
				(width 0.1524)
				(type default)
			)
			(layer "F.SilkS")
		)
		(fp_poly
			(pts
				(xy -1.524 -1.778) (xy 1.524 -1.778) (xy 1.524 1.778) (xy -1.524 1.778)
			)
			(stroke
				(width 0)
				(type default)
			)
			(fill no)
			(layer "F.CrtYd")
		)
		(fp_poly
			(pts
				(xy -1.524 -1.778) (xy 1.524 -1.778) (xy 1.524 1.778) (xy -1.524 1.778)
			)
			(stroke
				(width 0)
				(type default)
			)
			(fill no)
			(layer "F.Fab")
		)
		(pad "1" smd rect
			(at -0.65024 0.9398 270)
			(size 0.4064 1.016)
			(layers "F.Cu" "F.Mask" "F.Paste")
			(net "P3V3_HDD0_LED")
		)
		(pad "2" smd rect
			(at 0 0.9398 270)
			(size 0.4064 1.016)
			(layers "F.Cu" "F.Mask" "F.Paste")
			(net "HDD0_LED_G")
		)
		(pad "3" smd rect
			(at 0.65024 0.9398 270)
			(size 0.4064 1.016)
			(layers "F.Cu" "F.Mask" "F.Paste")
			(net "P5VA")
		)
		(pad "4" smd rect
			(at 0.65024 -0.9398 270)
			(size 0.4064 1.016)
			(layers "F.Cu" "F.Mask" "F.Paste")
			(net "P5VA_HDD0_LED")
		)
		(pad "5" smd rect
			(at 0 -0.9398 270)
			(size 0.4064 1.016)
			(layers "F.Cu" "F.Mask" "F.Paste")
			(net "HDD0_LED_G")
		)
		(pad "6" smd rect
			(at -0.65024 -0.9398 270)
			(size 0.4064 1.016)
			(layers "F.Cu" "F.Mask" "F.Paste")
			(net "P3V3")
		)
	)
	(footprint ""
		(layer "F.Cu")
		(at 193.167 -193.421 90)
		(property "Reference" "D18"
			(at 0 0 90)
			(layer "F.SilkS")
			(hide yes)
			(effects
				(font
					(size 1.27 1.27)
				)
			)
		)
		(property "Value" "RB551V30-1-GP"
			(at 0 -6.7818 90)
			(unlocked yes)
			(layer "F.Fab")
			(hide yes)
			(effects
				(font
					(size 1.016 1.016)
					(thickness 0.1524)
				)
			)
		)
		(property "Device Type" "SOD323AKH44"
			(at 0 -8.6868 90)
			(unlocked yes)
			(layer "F.Fab")
			(hide yes)
			(effects
				(font
					(size 1.016 1.016)
					(thickness 0.1524)
				)
			)
		)
		(duplicate_pad_numbers_are_jumpers no)
		(fp_line
			(start 0.889 -1.9304)
			(end 0.889 2.159)
			(stroke
				(width 0.1524)
				(type default)
			)
			(layer "F.SilkS")
		)
		(fp_line
			(start -0.889 -1.9304)
			(end 0.889 -1.9304)
			(stroke
				(width 0.1524)
				(type default)
			)
			(layer "F.SilkS")
		)
		(fp_line
			(start 0.762 2.0574)
			(end -0.762 2.0574)
			(stroke
				(width 0.508)
				(type default)
			)
			(layer "F.SilkS")
		)
		(fp_line
			(start 0.889 2.159)
			(end -0.889 2.159)
			(stroke
				(width 0.1524)
				(type default)
			)
			(layer "F.SilkS")
		)
		(fp_line
			(start -0.889 2.159)
			(end -0.889 -1.9304)
			(stroke
				(width 0.1524)
				(type default)
			)
			(layer "F.SilkS")
		)
		(fp_rect
			(start -1.016 2.3114)
			(end 1.016 -2.0066)
			(stroke
				(width 0)
				(type default)
			)
			(fill no)
			(layer "F.CrtYd")
		)
		(fp_poly
			(pts
				(xy -1.016 -2.0066) (xy 1.016 -2.0066) (xy 1.016 2.3114) (xy -1.016 2.3114)
			)
			(stroke
				(width 0)
				(type default)
			)
			(fill no)
			(layer "F.Fab")
		)
		(pad "A" smd rect
			(at 0 -1.143 90)
			(size 0.5588 1.016)
			(layers "F.Cu" "F.Mask" "F.Paste")
			(net "SW_HDD3_R")
		)
		(pad "K" smd rect
			(at 0 1.143 90)
			(size 0.5588 1.016)
			(layers "F.Cu" "F.Mask" "F.Paste")
			(net "SW_HDD3_N")
		)
	)
	(footprint ""
		(layer "F.Cu")
		(at 194.183 -77.851)
		(property "Reference" "C171"
			(at 0 0 0)
			(layer "F.SilkS")
			(hide yes)
			(effects
				(font
					(size 1.27 1.27)
				)
			)
		)
		(property "Value" "SCD1U10V2KX-5GP"
			(at 1.1811 -2.7051 0)
			(unlocked yes)
			(layer "F.Fab")
			(hide yes)
			(effects
				(font
					(size 1.016 1.016)
					(thickness 0.1524)
				)
			)
		)
		(property "Device Type" "C402H22"
			(at 1.1811 -4.2291 0)
			(unlocked yes)
			(layer "F.Fab")
			(hide yes)
			(effects
				(font
					(size 1.016 1.016)
					(thickness 0.1524)
				)
			)
		)
		(duplicate_pad_numbers_are_jumpers no)
		(fp_rect
			(start -0.4318 0.9525)
			(end 0.4318 -0.9525)
			(stroke
				(width 0)
				(type default)
			)
			(fill no)
			(layer "F.CrtYd")
		)
		(fp_rect
			(start -0.4318 0.9525)
			(end 0.4318 -0.9525)
			(stroke
				(width 0)
				(type default)
			)
			(fill no)
			(layer "F.Fab")
		)
		(pad "1" smd custom
			(at 0 -0.4445)
			(size 0.1524 0.1524)
			(layers "F.Cu" "F.Mask" "F.Paste")
			(net "P3V3")
			(options
				(clearance outline)
				(anchor circle)
			)
			(primitives
				(gr_poly
					(pts
						(arc
							(start 0.3048 -0.2032)
							(mid 0.275042 -0.275042)
							(end 0.2032 -0.3048)
						)
						(arc
							(start -0.2032 -0.3048)
							(mid -0.275042 -0.275042)
							(end -0.3048 -0.2032)
						)
						(arc
							(start -0.3048 0.2032)
							(mid -0.275042 0.275042)
							(end -0.2032 0.3048)
						)
						(arc
							(start 0.2032 0.3048)
							(mid 0.275042 0.275042)
							(end 0.3048 0.2032)
						)
					)
					(width 0)
					(fill yes)
				)
			)
		)
		(pad "2" smd custom
			(at 0 0.4445)
			(size 0.1524 0.1524)
			(layers "F.Cu" "F.Mask" "F.Paste")
			(net "GND")
			(options
				(clearance outline)
				(anchor circle)
			)
			(primitives
				(gr_poly
					(pts
						(arc
							(start 0.3048 -0.2032)
							(mid 0.275042 -0.275042)
							(end 0.2032 -0.3048)
						)
						(arc
							(start -0.2032 -0.3048)
							(mid -0.275042 -0.275042)
							(end -0.3048 -0.2032)
						)
						(arc
							(start -0.3048 0.2032)
							(mid -0.275042 0.275042)
							(end -0.2032 0.3048)
						)
						(arc
							(start 0.2032 0.3048)
							(mid 0.275042 0.275042)
							(end 0.3048 0.2032)
						)
					)
					(width 0)
					(fill yes)
				)
			)
		)
	)
	(footprint ""
		(layer "F.Cu")
		(at 51.180746 -25.2857 180)
		(property "Reference" "PR17"
			(at 0 0 180)
			(layer "F.SilkS")
			(hide yes)
			(effects
				(font
					(size 1.27 1.27)
				)
			)
		)
		(property "Value" "2K49R2F-GP"
			(at 0.064008 -3.993896 180)
			(unlocked yes)
			(layer "F.Fab")
			(hide yes)
			(effects
				(font
					(size 1.016 1.016)
					(thickness 0.1524)
				)
			)
		)
		(property "Device Type" "R402H16"
			(at 0.064008 -5.517896 180)
			(unlocked yes)
			(layer "F.Fab")
			(hide yes)
			(effects
				(font
					(size 1.016 1.016)
					(thickness 0.1524)
				)
			)
		)
		(duplicate_pad_numbers_are_jumpers no)
		(fp_line
			(start 0.508 -0.9398)
			(end -0.508 -0.9398)
			(stroke
				(width 0.1524)
				(type default)
			)
			(layer "F.SilkS")
		)
		(fp_line
			(start -0.508 -0.9398)
			(end -0.508 0.9398)
			(stroke
				(width 0.1524)
				(type default)
			)
			(layer "F.SilkS")
		)
		(fp_rect
			(start -0.508 0.9398)
			(end 0.508 -0.9398)
			(stroke
				(width 0)
				(type default)
			)
			(fill no)
			(layer "F.CrtYd")
		)
		(fp_rect
			(start -0.508 0.9398)
			(end 0.508 -0.9398)
			(stroke
				(width 0)
				(type default)
			)
			(fill no)
			(layer "F.Fab")
		)
		(pad "1" smd custom
			(at 0 -0.4445 180)
			(size 0.1397 0.1397)
			(layers "F.Cu" "F.Mask" "F.Paste")
			(net "P5VB_EN")
			(options
				(clearance outline)
				(anchor circle)
			)
			(primitives
				(gr_poly
					(pts
						(arc
							(start -0.1778 -0.2794)
							(mid -0.249642 -0.249642)
							(end -0.2794 -0.1778)
						)
						(arc
							(start -0.2794 0.1778)
							(mid -0.249642 0.249642)
							(end -0.1778 0.2794)
						)
						(arc
							(start 0.1778 0.2794)
							(mid 0.249642 0.249642)
							(end 0.2794 0.1778)
						)
						(arc
							(start 0.2794 -0.1778)
							(mid 0.249642 -0.249642)
							(end 0.1778 -0.2794)
						)
					)
					(width 0)
					(fill yes)
				)
			)
		)
		(pad "2" smd custom
			(at 0 0.4445 180)
			(size 0.1397 0.1397)
			(layers "F.Cu" "F.Mask" "F.Paste")
			(net "GND")
			(options
				(clearance outline)
				(anchor circle)
			)
			(primitives
				(gr_poly
					(pts
						(arc
							(start -0.1778 -0.2794)
							(mid -0.249642 -0.249642)
							(end -0.2794 -0.1778)
						)
						(arc
							(start -0.2794 0.1778)
							(mid -0.249642 0.249642)
							(end -0.1778 0.2794)
						)
						(arc
							(start 0.1778 0.2794)
							(mid 0.249642 0.249642)
							(end 0.2794 0.1778)
						)
						(arc
							(start 0.2794 -0.1778)
							(mid 0.249642 -0.249642)
							(end 0.1778 -0.2794)
						)
					)
					(width 0)
					(fill yes)
				)
			)
		)
	)
	(footprint ""
		(layer "F.Cu")
		(at 74.421746 -22.380702 180)
		(property "Reference" "C332"
			(at 0 0 180)
			(layer "F.SilkS")
			(hide yes)
			(effects
				(font
					(size 1.27 1.27)
				)
			)
		)
		(property "Value" "SCD01U50V2KX-1GP"
			(at 1.1811 -2.7051 180)
			(unlocked yes)
			(layer "F.Fab")
			(hide yes)
			(effects
				(font
					(size 1.016 1.016)
					(thickness 0.1524)
				)
			)
		)
		(property "Device Type" "C402H22"
			(at 1.1811 -4.2291 180)
			(unlocked yes)
			(layer "F.Fab")
			(hide yes)
			(effects
				(font
					(size 1.016 1.016)
					(thickness 0.1524)
				)
			)
		)
		(duplicate_pad_numbers_are_jumpers no)
		(fp_rect
			(start -0.4318 0.9525)
			(end 0.4318 -0.9525)
			(stroke
				(width 0)
				(type default)
			)
			(fill no)
			(layer "F.CrtYd")
		)
		(fp_rect
			(start -0.4318 0.9525)
			(end 0.4318 -0.9525)
			(stroke
				(width 0)
				(type default)
			)
			(fill no)
			(layer "F.Fab")
		)
		(pad "1" smd custom
			(at 0 -0.4445 180)
			(size 0.1524 0.1524)
			(layers "F.Cu" "F.Mask" "F.Paste")
			(net "HDD_PRSNT_NET14")
			(options
				(clearance outline)
				(anchor circle)
			)
			(primitives
				(gr_poly
					(pts
						(arc
							(start 0.3048 -0.2032)
							(mid 0.275042 -0.275042)
							(end 0.2032 -0.3048)
						)
						(arc
							(start -0.2032 -0.3048)
							(mid -0.275042 -0.275042)
							(end -0.3048 -0.2032)
						)
						(arc
							(start -0.3048 0.2032)
							(mid -0.275042 0.275042)
							(end -0.2032 0.3048)
						)
						(arc
							(start 0.2032 0.3048)
							(mid 0.275042 0.275042)
							(end 0.3048 0.2032)
						)
					)
					(width 0)
					(fill yes)
				)
			)
		)
		(pad "2" smd custom
			(at 0 0.4445 180)
			(size 0.1524 0.1524)
			(layers "F.Cu" "F.Mask" "F.Paste")
			(net "GND")
			(options
				(clearance outline)
				(anchor circle)
			)
			(primitives
				(gr_poly
					(pts
						(arc
							(start 0.3048 -0.2032)
							(mid 0.275042 -0.275042)
							(end 0.2032 -0.3048)
						)
						(arc
							(start -0.2032 -0.3048)
							(mid -0.275042 -0.275042)
							(end -0.3048 -0.2032)
						)
						(arc
							(start -0.3048 0.2032)
							(mid -0.275042 0.275042)
							(end -0.2032 0.3048)
						)
						(arc
							(start 0.2032 0.3048)
							(mid 0.275042 0.275042)
							(end 0.3048 0.2032)
						)
					)
					(width 0)
					(fill yes)
				)
			)
		)
	)
	(footprint ""
		(layer "F.Cu")
		(at 218.185746 -78.4987 180)
		(property "Reference" "C172"
			(at 0 0 180)
			(layer "F.SilkS")
			(hide yes)
			(effects
				(font
					(size 1.27 1.27)
				)
			)
		)
		(property "Value" "SC1U16V3KX-5GP"
			(at 0 -2.8194 180)
			(unlocked yes)
			(layer "F.Fab")
			(hide yes)
			(effects
				(font
					(size 1.016 1.016)
					(thickness 0.1524)
				)
			)
		)
		(property "Device Type" "C603H36"
			(at 0 -4.3434 180)
			(unlocked yes)
			(layer "F.Fab")
			(hide yes)
			(effects
				(font
					(size 1.016 1.016)
					(thickness 0.1524)
				)
			)
		)
		(duplicate_pad_numbers_are_jumpers no)
		(fp_line
			(start 0.508 0)
			(end -0.508 0)
			(stroke
				(width 0.2032)
				(type default)
			)
			(layer "F.SilkS")
		)
		(fp_rect
			(start -0.5842 1.3335)
			(end 0.5842 -1.3335)
			(stroke
				(width 0)
				(type default)
			)
			(fill no)
			(layer "F.CrtYd")
		)
		(fp_rect
			(start -0.5842 1.3335)
			(end 0.5842 -1.3335)
			(stroke
				(width 0)
				(type default)
			)
			(fill no)
			(layer "F.Fab")
		)
		(pad "1" smd custom
			(at 0 -0.762 180)
			(size 0.2159 0.2159)
			(layers "F.Cu" "F.Mask" "F.Paste")
			(net "P5V_HDD4")
			(options
				(clearance outline)
				(anchor circle)
			)
			(primitives
				(gr_poly
					(pts
						(arc
							(start -0.3302 -0.4318)
							(mid -0.402042 -0.402042)
							(end -0.4318 -0.3302)
						)
						(arc
							(start -0.4318 0.3302)
							(mid -0.402042 0.402042)
							(end -0.3302 0.4318)
						)
						(arc
							(start 0.3302 0.4318)
							(mid 0.402042 0.402042)
							(end 0.4318 0.3302)
						)
						(arc
							(start 0.4318 -0.3302)
							(mid 0.402042 -0.402042)
							(end 0.3302 -0.4318)
						)
					)
					(width 0)
					(fill yes)
				)
			)
		)
		(pad "2" smd custom
			(at 0 0.762 180)
			(size 0.2159 0.2159)
			(layers "F.Cu" "F.Mask" "F.Paste")
			(net "GND")
			(options
				(clearance outline)
				(anchor circle)
			)
			(primitives
				(gr_poly
					(pts
						(arc
							(start -0.3302 -0.4318)
							(mid -0.402042 -0.402042)
							(end -0.4318 -0.3302)
						)
						(arc
							(start -0.4318 0.3302)
							(mid -0.402042 0.402042)
							(end -0.3302 0.4318)
						)
						(arc
							(start 0.3302 0.4318)
							(mid 0.402042 0.402042)
							(end 0.4318 0.3302)
						)
						(arc
							(start 0.4318 -0.3302)
							(mid 0.402042 -0.402042)
							(end 0.3302 -0.4318)
						)
					)
					(width 0)
					(fill yes)
				)
			)
		)
	)
	(footprint ""
		(layer "F.Cu")
		(at 57.276746 -183.0197 180)
		(property "Reference" "C237"
			(at 0 0 180)
			(layer "F.SilkS")
			(hide yes)
			(effects
				(font
					(size 1.27 1.27)
				)
			)
		)
		(property "Value" "SC10U16V6KX-2GP"
			(at -0.0762 -5.1308 180)
			(unlocked yes)
			(layer "F.Fab")
			(hide yes)
			(effects
				(font
					(size 1.016 1.016)
					(thickness 0.1524)
				)
			)
		)
		(property "Device Type" "C1206H71"
			(at -0.127 -6.6548 180)
			(unlocked yes)
			(layer "F.Fab")
			(hide yes)
			(effects
				(font
					(size 1.016 1.016)
					(thickness 0.1524)
				)
			)
		)
		(duplicate_pad_numbers_are_jumpers no)
		(fp_line
			(start 1.016 2.2352)
			(end -1.016 2.2352)
			(stroke
				(width 0.1524)
				(type default)
			)
			(layer "F.SilkS")
		)
		(fp_line
			(start 1.016 0.8382)
			(end 1.016 2.2352)
			(stroke
				(width 0.1524)
				(type default)
			)
			(layer "F.SilkS")
		)
		(fp_line
			(start 1.016 -2.2352)
			(end 1.016 -0.8382)
			(stroke
				(width 0.1524)
				(type default)
			)
			(layer "F.SilkS")
		)
		(fp_line
			(start -1.016 2.2352)
			(end -1.016 0.8382)
			(stroke
				(width 0.1524)
				(type default)
			)
			(layer "F.SilkS")
		)
		(fp_line
			(start -1.016 -0.8382)
			(end -1.016 -2.2352)
			(stroke
				(width 0.1524)
				(type default)
			)
			(layer "F.SilkS")
		)
		(fp_line
			(start -1.016 -2.2352)
			(end 1.016 -2.2352)
			(stroke
				(width 0.1524)
				(type default)
			)
			(layer "F.SilkS")
		)
		(fp_rect
			(start -1.0922 2.3114)
			(end 1.0922 -2.3114)
			(stroke
				(width 0)
				(type default)
			)
			(fill no)
			(layer "F.CrtYd")
		)
		(fp_poly
			(pts
				(xy 1.0922 -2.3114) (xy 1.0922 2.3114) (xy -1.0922 2.3114) (xy -1.0922 -2.3114)
			)
			(stroke
				(width 0)
				(type default)
			)
			(fill no)
			(layer "F.Fab")
		)
		(pad "1" smd rect
			(at 0 -1.397 180)
			(size 1.651 1.27)
			(layers "F.Cu" "F.Mask" "F.Paste")
			(net "P5V_HDD8")
		)
		(pad "2" smd rect
			(at 0 1.397 180)
			(size 1.651 1.27)
			(layers "F.Cu" "F.Mask" "F.Paste")
			(net "GND")
		)
	)
)
